(kicad_pcb
	(version 20260206)
	(generator "pcbnew")
	(generator_version "10.0")
	(general
		(thickness 1.6)
		(legacy_teardrops no)
	)
	(paper "A4")
	(title_block
		(title "Bryce Canyon_F.DPB_16315-1-OCP.brd")
		(comment 1 "Bryce Canyon / footprints 530-536 of 2223")
	)
	(layers
		(0 "F.Cu" signal "TOP")
		(4 "In1.Cu" signal "L2GND")
		(6 "In2.Cu" signal "L3")
		(8 "In3.Cu" signal "L4GND")
		(10 "In4.Cu" signal "L5")
		(12 "In5.Cu" signal "L6VCC")
		(14 "In6.Cu" signal "L7VCC")
		(16 "In7.Cu" signal "L8")
		(18 "In8.Cu" signal "L9GND")
		(20 "In9.Cu" signal "L10")
		(22 "In10.Cu" signal "L11GND")
		(2 "B.Cu" signal "BOTTOM")
		(9 "F.Adhes" user "F.Adhesive")
		(11 "B.Adhes" user "B.Adhesive")
		(13 "F.Paste" user "Package Geometry/Pastemask Top")
		(15 "B.Paste" user "Package Geometry/Pastemask Bottom")
		(5 "F.SilkS" user "Ref Des/Silkscreen Top")
		(7 "B.SilkS" user "Ref Des/Silkscreen Bottom")
		(1 "F.Mask" user "Board Geometry/Soldermask Top")
		(3 "B.Mask" user "Board Geometry/Soldermask Bottom")
		(17 "Dwgs.User" user "User.Drawings")
		(19 "Cmts.User" user "User.Comments")
		(21 "Eco1.User" user "User.Eco1")
		(23 "Eco2.User" user "User.Eco2")
		(25 "Edge.Cuts" user "Board Geometry/Outline")
		(27 "Margin" user)
		(31 "F.CrtYd" user "Package Geometry/Place Bound Top")
		(29 "B.CrtYd" user "Package Geometry/Place Bound Bottom")
		(35 "F.Fab" user "Ref Des/Assembly Top")
		(33 "B.Fab" user "Ref Des/Assembly Bottom")
	)
	(footprint ""
		(layer "F.Cu")
		(at 255.0414 18.219928 180)
		(property "Reference" "R638"
			(at 0 0 180)
			(layer "F.SilkS")
			(hide yes)
			(effects
				(font
					(size 1.27 1.27)
				)
			)
		)
		(property "Value" "10KR2F-2-GP"
			(at 0.064008 -3.993896 180)
			(unlocked yes)
			(layer "F.Fab")
			(hide yes)
			(effects
				(font
					(size 1.016 1.016)
					(thickness 0.1524)
				)
			)
		)
		(property "Device Type" "R402H16"
			(at 0.064008 -5.517896 180)
			(unlocked yes)
			(layer "F.Fab")
			(hide yes)
			(effects
				(font
					(size 1.016 1.016)
					(thickness 0.1524)
				)
			)
		)
		(duplicate_pad_numbers_are_jumpers no)
		(fp_line
			(start 0.508 -0.9398)
			(end -0.508 -0.9398)
			(stroke
				(width 0.1524)
				(type default)
			)
			(layer "F.SilkS")
		)
		(fp_line
			(start -0.508 -0.9398)
			(end -0.508 0.9398)
			(stroke
				(width 0.1524)
				(type default)
			)
			(layer "F.SilkS")
		)
		(fp_rect
			(start -0.508 0.9398)
			(end 0.508 -0.9398)
			(stroke
				(width 0)
				(type default)
			)
			(fill no)
			(layer "F.CrtYd")
		)
		(fp_rect
			(start -0.508 0.9398)
			(end 0.508 -0.9398)
			(stroke
				(width 0)
				(type default)
			)
			(fill no)
			(layer "F.Fab")
		)
		(pad "1" smd custom
			(at 0 -0.4445 180)
			(size 0.1397 0.1397)
			(layers "F.Cu" "F.Mask" "F.Paste")
			(net "P3V3_STBY_A")
			(options
				(clearance outline)
				(anchor circle)
			)
			(primitives
				(gr_poly
					(pts
						(arc
							(start -0.1778 -0.2794)
							(mid -0.249642 -0.249642)
							(end -0.2794 -0.1778)
						)
						(arc
							(start -0.2794 0.1778)
							(mid -0.249642 0.249642)
							(end -0.1778 0.2794)
						)
						(arc
							(start 0.1778 0.2794)
							(mid 0.249642 0.249642)
							(end 0.2794 0.1778)
						)
						(arc
							(start 0.2794 -0.1778)
							(mid 0.249642 -0.249642)
							(end 0.1778 -0.2794)
						)
					)
					(width 0)
					(fill yes)
				)
			)
		)
		(pad "2" smd custom
			(at 0 0.4445 180)
			(size 0.1397 0.1397)
			(layers "F.Cu" "F.Mask" "F.Paste")
			(net "SCC_A_PWR_LED")
			(options
				(clearance outline)
				(anchor circle)
			)
			(primitives
				(gr_poly
					(pts
						(arc
							(start -0.1778 -0.2794)
							(mid -0.249642 -0.249642)
							(end -0.2794 -0.1778)
						)
						(arc
							(start -0.2794 0.1778)
							(mid -0.249642 0.249642)
							(end -0.1778 0.2794)
						)
						(arc
							(start 0.1778 0.2794)
							(mid 0.249642 0.249642)
							(end 0.2794 0.1778)
						)
						(arc
							(start 0.2794 -0.1778)
							(mid 0.249642 -0.249642)
							(end 0.1778 -0.2794)
						)
					)
					(width 0)
					(fill yes)
				)
			)
		)
	)
	(footprint ""
		(layer "F.Cu")
		(at 285.623 -272.3134)
		(property "Reference" "R127"
			(at 0 0 0)
			(layer "F.SilkS")
			(hide yes)
			(effects
				(font
					(size 1.27 1.27)
				)
			)
		)
		(property "Value" "4K7R2F-GP"
			(at 0.064008 -3.993896 0)
			(unlocked yes)
			(layer "F.Fab")
			(hide yes)
			(effects
				(font
					(size 1.016 1.016)
					(thickness 0.1524)
				)
			)
		)
		(property "Device Type" "R402H16"
			(at 0.064008 -5.517896 0)
			(unlocked yes)
			(layer "F.Fab")
			(hide yes)
			(effects
				(font
					(size 1.016 1.016)
					(thickness 0.1524)
				)
			)
		)
		(duplicate_pad_numbers_are_jumpers no)
		(fp_line
			(start -0.508 -0.9398)
			(end -0.508 0.9398)
			(stroke
				(width 0.1524)
				(type default)
			)
			(layer "F.SilkS")
		)
		(fp_line
			(start 0.508 -0.9398)
			(end -0.508 -0.9398)
			(stroke
				(width 0.1524)
				(type default)
			)
			(layer "F.SilkS")
		)
		(fp_rect
			(start -0.508 0.9398)
			(end 0.508 -0.9398)
			(stroke
				(width 0)
				(type default)
			)
			(fill no)
			(layer "F.CrtYd")
		)
		(fp_rect
			(start -0.508 0.9398)
			(end 0.508 -0.9398)
			(stroke
				(width 0)
				(type default)
			)
			(fill no)
			(layer "F.Fab")
		)
		(pad "1" smd custom
			(at 0 -0.4445)
			(size 0.1397 0.1397)
			(layers "F.Cu" "F.Mask" "F.Paste")
			(net "IO_EXP2_HDD_FAULT_A2")
			(options
				(clearance outline)
				(anchor circle)
			)
			(primitives
				(gr_poly
					(pts
						(arc
							(start -0.1778 -0.2794)
							(mid -0.249642 -0.249642)
							(end -0.2794 -0.1778)
						)
						(arc
							(start -0.2794 0.1778)
							(mid -0.249642 0.249642)
							(end -0.1778 0.2794)
						)
						(arc
							(start 0.1778 0.2794)
							(mid 0.249642 0.249642)
							(end 0.2794 0.1778)
						)
						(arc
							(start 0.2794 -0.1778)
							(mid 0.249642 -0.249642)
							(end 0.1778 -0.2794)
						)
					)
					(width 0)
					(fill yes)
				)
			)
		)
		(pad "2" smd custom
			(at 0 0.4445)
			(size 0.1397 0.1397)
			(layers "F.Cu" "F.Mask" "F.Paste")
			(net "GND")
			(options
				(clearance outline)
				(anchor circle)
			)
			(primitives
				(gr_poly
					(pts
						(arc
							(start -0.1778 -0.2794)
							(mid -0.249642 -0.249642)
							(end -0.2794 -0.1778)
						)
						(arc
							(start -0.2794 0.1778)
							(mid -0.249642 0.249642)
							(end -0.1778 0.2794)
						)
						(arc
							(start 0.1778 0.2794)
							(mid 0.249642 0.249642)
							(end 0.2794 0.1778)
						)
						(arc
							(start 0.2794 -0.1778)
							(mid 0.249642 -0.249642)
							(end 0.1778 -0.2794)
						)
					)
					(width 0)
					(fill yes)
				)
			)
		)
	)
	(footprint ""
		(layer "F.Cu")
		(at 368.862102 -277.792942 90)
		(property "Reference" "D7"
			(at 0 0 90)
			(layer "F.SilkS")
			(hide yes)
			(effects
				(font
					(size 1.27 1.27)
				)
			)
		)
		(property "Value" "RB551V30-GP"
			(at 0 -6.7818 90)
			(unlocked yes)
			(layer "F.Fab")
			(hide yes)
			(effects
				(font
					(size 1.016 1.016)
					(thickness 0.1524)
				)
			)
		)
		(property "Device Type" "SOD323AKH38"
			(at 0 -8.6868 90)
			(unlocked yes)
			(layer "F.Fab")
			(hide yes)
			(effects
				(font
					(size 1.016 1.016)
					(thickness 0.1524)
				)
			)
		)
		(duplicate_pad_numbers_are_jumpers no)
		(fp_line
			(start 0.889 -1.9304)
			(end 0.889 2.159)
			(stroke
				(width 0.1524)
				(type default)
			)
			(layer "F.SilkS")
		)
		(fp_line
			(start -0.889 -1.9304)
			(end 0.889 -1.9304)
			(stroke
				(width 0.1524)
				(type default)
			)
			(layer "F.SilkS")
		)
		(fp_line
			(start 0.762 2.0574)
			(end -0.762 2.0574)
			(stroke
				(width 0.508)
				(type default)
			)
			(layer "F.SilkS")
		)
		(fp_line
			(start 0.889 2.159)
			(end -0.889 2.159)
			(stroke
				(width 0.1524)
				(type default)
			)
			(layer "F.SilkS")
		)
		(fp_line
			(start -0.889 2.159)
			(end -0.889 -1.9304)
			(stroke
				(width 0.1524)
				(type default)
			)
			(layer "F.SilkS")
		)
		(fp_rect
			(start -1.016 2.3114)
			(end 1.016 -2.0066)
			(stroke
				(width 0)
				(type default)
			)
			(fill no)
			(layer "F.CrtYd")
		)
		(fp_poly
			(pts
				(xy -1.016 -2.0066) (xy 1.016 -2.0066) (xy 1.016 2.3114) (xy -1.016 2.3114)
			)
			(stroke
				(width 0)
				(type default)
			)
			(fill no)
			(layer "F.Fab")
		)
		(pad "A" smd rect
			(at 0 -1.143 90)
			(size 0.5588 1.016)
			(layers "F.Cu" "F.Mask" "F.Paste")
			(net "SW_HDD_R7")
		)
		(pad "K" smd rect
			(at 0 1.143 90)
			(size 0.5588 1.016)
			(layers "F.Cu" "F.Mask" "F.Paste")
			(net "SW_HDD_N7")
		)
	)
	(footprint ""
		(layer "F.Cu")
		(at 77.942948 -169.523918 90)
		(property "Reference" "C231"
			(at 0 0 90)
			(layer "F.SilkS")
			(hide yes)
			(effects
				(font
					(size 1.27 1.27)
				)
			)
		)
		(property "Value" "SCD033U25V2KX-GP"
			(at 1.1811 -2.7051 90)
			(unlocked yes)
			(layer "F.Fab")
			(hide yes)
			(effects
				(font
					(size 1.016 1.016)
					(thickness 0.1524)
				)
			)
		)
		(property "Device Type" "C402H22"
			(at 1.1811 -4.2291 90)
			(unlocked yes)
			(layer "F.Fab")
			(hide yes)
			(effects
				(font
					(size 1.016 1.016)
					(thickness 0.1524)
				)
			)
		)
		(duplicate_pad_numbers_are_jumpers no)
		(fp_rect
			(start -0.4318 0.9525)
			(end 0.4318 -0.9525)
			(stroke
				(width 0)
				(type default)
			)
			(fill no)
			(layer "F.CrtYd")
		)
		(fp_rect
			(start -0.4318 0.9525)
			(end 0.4318 -0.9525)
			(stroke
				(width 0)
				(type default)
			)
			(fill no)
			(layer "F.Fab")
		)
		(pad "1" smd custom
			(at 0 -0.4445 90)
			(size 0.1524 0.1524)
			(layers "F.Cu" "F.Mask" "F.Paste")
			(net "P12V_A")
			(options
				(clearance outline)
				(anchor circle)
			)
			(primitives
				(gr_poly
					(pts
						(arc
							(start 0.3048 -0.2032)
							(mid 0.275042 -0.275042)
							(end 0.2032 -0.3048)
						)
						(arc
							(start -0.2032 -0.3048)
							(mid -0.275042 -0.275042)
							(end -0.3048 -0.2032)
						)
						(arc
							(start -0.3048 0.2032)
							(mid -0.275042 0.275042)
							(end -0.2032 0.3048)
						)
						(arc
							(start 0.2032 0.3048)
							(mid 0.275042 0.275042)
							(end 0.3048 0.2032)
						)
					)
					(width 0)
					(fill yes)
				)
			)
		)
		(pad "2" smd custom
			(at 0 0.4445 90)
			(size 0.1524 0.1524)
			(layers "F.Cu" "F.Mask" "F.Paste")
			(net "SW_HDD_N14")
			(options
				(clearance outline)
				(anchor circle)
			)
			(primitives
				(gr_poly
					(pts
						(arc
							(start 0.3048 -0.2032)
							(mid 0.275042 -0.275042)
							(end 0.2032 -0.3048)
						)
						(arc
							(start -0.2032 -0.3048)
							(mid -0.275042 -0.275042)
							(end -0.3048 -0.2032)
						)
						(arc
							(start -0.3048 0.2032)
							(mid -0.275042 0.275042)
							(end -0.2032 0.3048)
						)
						(arc
							(start 0.2032 0.3048)
							(mid 0.275042 0.275042)
							(end 0.3048 0.2032)
						)
					)
					(width 0)
					(fill yes)
				)
			)
		)
	)
	(footprint ""
		(layer "F.Cu")
		(at 330.67498 -207.79994)
		(property "Reference" ""
			(at 0 0 0)
			(layer "F.SilkS")
			(hide yes)
			(effects
				(font
					(size 1.27 1.27)
				)
			)
		)
		(property "Value" "*"
			(at -8.398764 -8.057642 0)
			(unlocked yes)
			(layer "F.Fab")
			(hide yes)
			(effects
				(font
					(size 1.016 1.016)
					(thickness 0.1524)
				)
			)
		)
		(duplicate_pad_numbers_are_jumpers no)
		(fp_poly
			(pts
				(arc
					(start 7.3152 0)
					(mid 0 7.3152)
					(end -7.3152 0)
				)
				(arc
					(start -7.3152 -5.9944)
					(mid 0 -13.3096)
					(end 7.3152 -5.9944)
				)
			)
			(stroke
				(width 0)
				(type default)
			)
			(fill no)
			(layer "B.CrtYd")
		)
		(fp_poly
			(pts
				(arc
					(start 7.3152 0)
					(mid 0 7.3152)
					(end -7.3152 0)
				)
				(arc
					(start -7.3152 -5.9944)
					(mid 0 -13.3096)
					(end 7.3152 -5.9944)
				)
			)
			(stroke
				(width 0)
				(type default)
			)
			(fill no)
			(layer "F.CrtYd")
		)
		(fp_poly
			(pts
				(arc
					(start 7.3152 0)
					(mid 0 7.3152)
					(end -7.3152 0)
				)
				(arc
					(start -7.3152 -5.9944)
					(mid 0 -13.3096)
					(end 7.3152 -5.9944)
				)
			)
			(stroke
				(width 0)
				(type default)
			)
			(fill no)
			(layer "B.Fab")
		)
		(fp_poly
			(pts
				(arc
					(start 7.3152 0)
					(mid 0 7.3152)
					(end -7.3152 0)
				)
				(arc
					(start -7.3152 -5.9944)
					(mid 0 -13.3096)
					(end 7.3152 -5.9944)
				)
			)
			(stroke
				(width 0)
				(type default)
			)
			(fill no)
			(layer "F.Fab")
		)
		(pad "1" thru_hole oval
			(at 0 0)
			(size 14.0208 20.0152)
			(drill 0.0254
				(offset 0 -2.9972)
			)
			(layers "*.Cu" "*.Mask")
			(remove_unused_layers no)
			(net "Net_100")
			(clearance -1.002284)
			(thermal_gap 0.1524)
			(padstack
				(mode front_inner_back)
				(layer "Inner"
					(shape custom)
					(size 2.928012 2.928012)
					(options
						(anchor circle)
					)
					(primitives
						(gr_poly
							(pts
								(arc
									(start 4.571746 -2.084324)
									(mid 0.000333 7.430372)
									(end -4.571492 -2.084324)
								)
								(arc
									(start -4.571492 -2.084324)
									(mid -3.570296 -3.611977)
									(end -2.875026 -5.30098)
								)
								(arc
									(start -2.875026 -5.30098)
									(mid 0.000217 -7.43089)
									(end 2.87528 -5.30098)
								)
								(arc
									(start 2.87528 -5.30098)
									(mid 3.570511 -3.611956)
									(end 4.571746 -2.084324)
								)
							)
							(width 0)
							(fill yes)
						)
					)
					(clearance 0.1524)
				)
				(layer "B.Cu"
					(shape oval)
					(size 14.0208 20.0152)
					(offset 0 -2.9972)
					(clearance -1.002284)
				)
			)
		)
		(zone
			(layers "F.Cu" "B.Cu" "In1.Cu" "In2.Cu" "In3.Cu" "In4.Cu" "In5.Cu" "In6.Cu"
				"In7.Cu" "In8.Cu" "In9.Cu" "In10.Cu"
			)
			(hatch none 0.5)
			(connect_pads
				(clearance 0)
			)
			(min_thickness 0.25)
			(keepout
				(tracks not_allowed)
				(vias allowed)
				(pads allowed)
				(copperpour not_allowed)
				(footprints allowed)
			)
			(placement
				(enabled no)
				(sheetname "")
			)
			(fill
				(thermal_gap 0.5)
				(thermal_bridge_width 0.5)
				(island_removal_mode 0)
			)
			(polygon
				(pts
					(arc
						(start 323.66458 -213.79434)
						(mid 330.67498 -220.80474)
						(end 337.68538 -213.79434)
					)
					(arc
						(start 337.68538 -207.79994)
						(mid 330.67498 -200.78954)
						(end 323.66458 -207.79994)
					)
				)
			)
		)
	)
	(footprint ""
		(layer "F.Cu")
		(at 367.287302 -160.735518 180)
		(property "Reference" "R584"
			(at 0 0 180)
			(layer "F.SilkS")
			(hide yes)
			(effects
				(font
					(size 1.27 1.27)
				)
			)
		)
		(property "Value" "0R2J-2-GP"
			(at 0.064008 -3.993896 180)
			(unlocked yes)
			(layer "F.Fab")
			(hide yes)
			(effects
				(font
					(size 1.016 1.016)
					(thickness 0.1524)
				)
			)
		)
		(property "Device Type" "R402H16"
			(at 0.064008 -5.517896 180)
			(unlocked yes)
			(layer "F.Fab")
			(hide yes)
			(effects
				(font
					(size 1.016 1.016)
					(thickness 0.1524)
				)
			)
		)
		(duplicate_pad_numbers_are_jumpers no)
		(fp_line
			(start 0.508 -0.9398)
			(end -0.508 -0.9398)
			(stroke
				(width 0.1524)
				(type default)
			)
			(layer "F.SilkS")
		)
		(fp_line
			(start -0.508 -0.9398)
			(end -0.508 0.9398)
			(stroke
				(width 0.1524)
				(type default)
			)
			(layer "F.SilkS")
		)
		(fp_rect
			(start -0.508 0.9398)
			(end 0.508 -0.9398)
			(stroke
				(width 0)
				(type default)
			)
			(fill no)
			(layer "F.CrtYd")
		)
		(fp_rect
			(start -0.508 0.9398)
			(end 0.508 -0.9398)
			(stroke
				(width 0)
				(type default)
			)
			(fill no)
			(layer "F.Fab")
		)
		(pad "1" smd custom
			(at 0 -0.4445 180)
			(size 0.1397 0.1397)
			(layers "F.Cu" "F.Mask" "F.Paste")
			(net "SW_HDD_G19")
			(options
				(clearance outline)
				(anchor circle)
			)
			(primitives
				(gr_poly
					(pts
						(arc
							(start -0.1778 -0.2794)
							(mid -0.249642 -0.249642)
							(end -0.2794 -0.1778)
						)
						(arc
							(start -0.2794 0.1778)
							(mid -0.249642 0.249642)
							(end -0.1778 0.2794)
						)
						(arc
							(start 0.1778 0.2794)
							(mid 0.249642 0.249642)
							(end 0.2794 0.1778)
						)
						(arc
							(start 0.2794 -0.1778)
							(mid 0.249642 -0.249642)
							(end 0.1778 -0.2794)
						)
					)
					(width 0)
					(fill yes)
				)
			)
		)
		(pad "2" smd custom
			(at 0 0.4445 180)
			(size 0.1397 0.1397)
			(layers "F.Cu" "F.Mask" "F.Paste")
			(net "SW_HDD_R19")
			(options
				(clearance outline)
				(anchor circle)
			)
			(primitives
				(gr_poly
					(pts
						(arc
							(start -0.1778 -0.2794)
							(mid -0.249642 -0.249642)
							(end -0.2794 -0.1778)
						)
						(arc
							(start -0.2794 0.1778)
							(mid -0.249642 0.249642)
							(end -0.1778 0.2794)
						)
						(arc
							(start 0.1778 0.2794)
							(mid 0.249642 0.249642)
							(end 0.2794 0.1778)
						)
						(arc
							(start 0.2794 -0.1778)
							(mid 0.249642 -0.249642)
							(end 0.1778 -0.2794)
						)
					)
					(width 0)
					(fill yes)
				)
			)
		)
	)
	(footprint ""
		(layer "F.Cu")
		(at 20.430998 -292.778942 -90)
		(property "Reference" "C508"
			(at 0 0 270)
			(layer "F.SilkS")
			(hide yes)
			(effects
				(font
					(size 1.27 1.27)
				)
			)
		)
		(property "Value" "SC1U16V3KX-5GP"
			(at 0 -2.8194 270)
			(unlocked yes)
			(layer "F.Fab")
			(hide yes)
			(effects
				(font
					(size 1.016 1.016)
					(thickness 0.1524)
				)
			)
		)
		(property "Device Type" "C603H36"
			(at 0 -4.3434 270)
			(unlocked yes)
			(layer "F.Fab")
			(hide yes)
			(effects
				(font
					(size 1.016 1.016)
					(thickness 0.1524)
				)
			)
		)
		(duplicate_pad_numbers_are_jumpers no)
		(fp_line
			(start 0.508 0)
			(end -0.508 0)
			(stroke
				(width 0.2032)
				(type default)
			)
			(layer "F.SilkS")
		)
		(fp_rect
			(start -0.5842 1.3335)
			(end 0.5842 -1.3335)
			(stroke
				(width 0)
				(type default)
			)
			(fill no)
			(layer "F.CrtYd")
		)
		(fp_rect
			(start -0.5842 1.3335)
			(end 0.5842 -1.3335)
			(stroke
				(width 0)
				(type default)
			)
			(fill no)
			(layer "F.Fab")
		)
		(pad "1" smd custom
			(at 0 -0.762 270)
			(size 0.2159 0.2159)
			(layers "F.Cu" "F.Mask" "F.Paste")
			(net "P5V_HDD0")
			(options
				(clearance outline)
				(anchor circle)
			)
			(primitives
				(gr_poly
					(pts
						(arc
							(start -0.3302 -0.4318)
							(mid -0.402042 -0.402042)
							(end -0.4318 -0.3302)
						)
						(arc
							(start -0.4318 0.3302)
							(mid -0.402042 0.402042)
							(end -0.3302 0.4318)
						)
						(arc
							(start 0.3302 0.4318)
							(mid 0.402042 0.402042)
							(end 0.4318 0.3302)
						)
						(arc
							(start 0.4318 -0.3302)
							(mid 0.402042 -0.402042)
							(end 0.3302 -0.4318)
						)
					)
					(width 0)
					(fill yes)
				)
			)
		)
		(pad "2" smd custom
			(at 0 0.762 270)
			(size 0.2159 0.2159)
			(layers "F.Cu" "F.Mask" "F.Paste")
			(net "GND")
			(options
				(clearance outline)
				(anchor circle)
			)
			(primitives
				(gr_poly
					(pts
						(arc
							(start -0.3302 -0.4318)
							(mid -0.402042 -0.402042)
							(end -0.4318 -0.3302)
						)
						(arc
							(start -0.4318 0.3302)
							(mid -0.402042 0.402042)
							(end -0.3302 0.4318)
						)
						(arc
							(start 0.3302 0.4318)
							(mid 0.402042 0.402042)
							(end 0.4318 0.3302)
						)
						(arc
							(start 0.4318 -0.3302)
							(mid 0.402042 -0.402042)
							(end 0.3302 -0.4318)
						)
					)
					(width 0)
					(fill yes)
				)
			)
		)
	)
)
